#ISCELL
  mstr_misc dns *
  *
#ISCELL
  pure_quanta quanta_title_block_c *
  *
#ISCELL
  pure_quanta_power cad_note *
  *
#ISCELL
  standard offpage *
  page137_i1
#CELL
  pure_quanta q_res *
  page137_i13
#CELL
  pure_quanta q_res *
  page137_i15
#CELL
  pure_quanta q_res *
  page137_i16
#ISCELL
  standard offpage *
  page137_i17
#ISCELL
  standard offpage *
  page137_i18
#ISCELL
  standard offpage *
  page137_i19
#ISCELL
  standard offpage *
  page137_i2
#ISCELL
  standard offpage *
  page137_i20
#ISCELL
  standard offpage *
  page137_i21
#ISCELL
  pure_quanta_power universal_gnd *
  page137_i24
#ISCELL
  pure_quanta_power universal_gnd *
  page137_i25
#CELL
  pure_quanta q_cap *
  page137_i26
#ISCELL
  pure_quanta_power universal_power *
  page137_i27
#ISCELL
  pure_quanta_power universal_gnd *
  page137_i28
#CELL
  pure_quanta q_cap *
  page137_i29
#ISCELL
  pure_quanta_power universal_gnd *
  page137_i3
#ISCELL
  pure_quanta_power vcc_core *
  page137_i30
#CELL
  pure_quanta q_res *
  page137_i31
#ISCELL
  pure_quanta_power vcc_core *
  page137_i32
#ISCELL
  standard offpage *
  page137_i37
#CELL
  pure_quanta q_res *
  page137_i40
#CELL
  pure_quanta q_res *
  page137_i41
#ISCELL
  pure_quanta_power vcc_core *
  page137_i42
#ISCELL
  pure_quanta_power vcc_core *
  page137_i43
#CELL
  pure_quanta q_res *
  page137_i44
#ISCELL
  pure_quanta_power vcc_core *
  page137_i45
#CELL
  pure_quanta q_res *
  page137_i46
#CELL
  pure_quanta pca9617adp *
  page137_i48
#ISCELL
  pure_quanta_power vcc_core *
  page137_i49
#ISCELL
  pure_quanta_power universal_gnd *
  page137_i5
#ISCELL
  pure_quanta_power vcc_core *
  page137_i50
#CELL
  pure_quanta pca9617adp *
  page137_i51
#ISCELL
  pure_quanta_power universal_power *
  page137_i52
#ISCELL
  pure_quanta_power vcc_core *
  page137_i54
#ISCELL
  pure_quanta_power universal_gnd *
  page137_i55
#CELL
  pure_quanta q_cap *
  page137_i56
#ISCELL
  pure_quanta_power universal_power *
  page137_i57
#ISCELL
  pure_quanta_power universal_gnd *
  page137_i58
#CELL
  pure_quanta q_cap *
  page137_i59
#CELL
  pure_quanta q_cap *
  page137_i6
#ISCELL
  pure_quanta_power universal_gnd *
  page137_i60
#ISCELL
  pure_quanta_power universal_power *
  page137_i61
#CELL
  pure_quanta q_res *
  page137_i62
#ISCELL
  standard offpage *
  page137_i63
#ISCELL
  standard offpage *
  page137_i64
#CELL
  pure_quanta q_res *
  page137_i67
#CELL
  pure_quanta q_res *
  page137_i68
#ISCELL
  standard offpage *
  page137_i69
#ISCELL
  pure_quanta_power universal_power *
  page137_i7
#ISCELL
  standard offpage *
  page137_i70
#CELL
  pure_quanta q_res *
  page137_i71
#CELL
  pure_quanta q_res *
  page137_i72
#CELL
  pure_quanta q_res *
  page137_i73
#ISCELL
  pure_quanta_power vcc_core *
  page137_i74
#ISCELL
  standard offpage *
  page137_i75
#ISCELL
  standard offpage *
  page137_i76
#ISCELL
  pure_quanta_power vcc_core *
  page137_i77
#CELL
  pure_quanta q_res *
  page137_i78
#CELL
  pure_quanta q_res *
  page137_i79
#CELL
  pure_quanta q_cap *
  page137_i8
#CELL
  pure_quanta q_res *
  page137_i80
#ISCELL
  standard offpage *
  page137_i81
#ISCELL
  standard offpage *
  page137_i82
#ISCELL
  standard offpage *
  page137_i83
#ISCELL
  standard offpage *
  page137_i84
#ISCELL
  standard offpage *
  page137_i87
#ISCELL
  standard offpage *
  page137_i88
#ISCELL
  standard offpage *
  page137_i89
#ISCELL
  pure_quanta_power universal_gnd *
  page137_i9
#ISCELL
  standard offpage *
  page137_i90
#CELL
  pure_quanta q_res *
  page137_i91
#CELL
  pure_quanta q_res *
  page137_i92
#CELL
  pure_quanta q_res *
  page137_i93
#CELL
  pure_quanta q_res *
  page137_i94
#CELL
  pure_quanta q_res *
  page137_i95
#CELL
  pure_quanta q_res *
  page137_i96
#CELL
  pure_quanta q_res *
  page137_i97
#CELL
  pure_quanta q_res *
  page137_i98
#CELL
  pure_quanta pca9617adp *
  page137_i99
